(kicad_pcb
	(version 20260206)
	(generator "pcbnew")
	(generator_version "10.0")
	(general
		(thickness 1.6)
		(legacy_teardrops no)
	)
	(paper "A4")
	(title_block
		(title "01162023_DA0F0TEBIF0_F0T_Expander_BD_F_brd_V02_OCP.brd")
		(comment 1 "Grand Teton / footprints 2228-2233 of 9728")
	)
	(layers
		(0 "F.Cu" signal "TOP")
		(4 "In1.Cu" signal "GND")
		(6 "In2.Cu" signal "VCC")
		(8 "In3.Cu" signal "VCC1")
		(10 "In4.Cu" signal "GND1")
		(12 "In5.Cu" signal "IN1")
		(14 "In6.Cu" signal "GND2")
		(16 "In7.Cu" signal "IN2")
		(18 "In8.Cu" signal "GND3")
		(20 "In9.Cu" signal "IN3")
		(22 "In10.Cu" signal "GND4")
		(24 "In11.Cu" signal "IN4")
		(26 "In12.Cu" signal "GND5")
		(28 "In13.Cu" signal "IN5")
		(30 "In14.Cu" signal "GND6")
		(32 "In15.Cu" signal "IN6")
		(34 "In16.Cu" signal "GND7")
		(2 "B.Cu" signal "BOTTOM")
		(9 "F.Adhes" user "F.Adhesive")
		(11 "B.Adhes" user "B.Adhesive")
		(13 "F.Paste" user "Package Geometry/Pastemask Top")
		(15 "B.Paste" user "Package Geometry/Pastemask Bottom")
		(5 "F.SilkS" user "Ref Des/Silkscreen Top")
		(7 "B.SilkS" user "Ref Des/Silkscreen Bottom")
		(1 "F.Mask" user "Board Geometry/Soldermask Top")
		(3 "B.Mask" user "Board Geometry/Soldermask Bottom")
		(17 "Dwgs.User" user "User.Drawings")
		(19 "Cmts.User" user "User.Comments")
		(21 "Eco1.User" user "User.Eco1")
		(23 "Eco2.User" user "User.Eco2")
		(25 "Edge.Cuts" user "Board Geometry/Outline")
		(27 "Margin" user)
		(31 "F.CrtYd" user "Package Geometry/Place Bound Top")
		(29 "B.CrtYd" user "Package Geometry/Place Bound Bottom")
		(35 "F.Fab" user "Ref Des/Assembly Top")
		(33 "B.Fab" user "Ref Des/Assembly Bottom")
	)
	(footprint ""
		(layer "F.Cu")
		(at 235.623608 -144.672812)
		(property "Reference" "R4194"
			(at 0 0 0)
			(layer "F.SilkS")
			(hide yes)
			(effects
				(font
					(size 1.27 1.27)
				)
			)
		)
		(property "Value" ""
			(at 0 0 0)
			(layer "F.Fab")
			(effects
				(font
					(size 1.27 1.27)
				)
			)
		)
		(duplicate_pad_numbers_are_jumpers no)
		(fp_line
			(start -0.7874 -0.4064)
			(end 0.7874 -0.4064)
			(stroke
				(width 0.1524)
				(type default)
			)
			(layer "F.SilkS")
		)
		(fp_line
			(start -0.7874 0.4064)
			(end -0.7874 -0.4064)
			(stroke
				(width 0.1524)
				(type default)
			)
			(layer "F.SilkS")
		)
		(fp_line
			(start 0.7874 -0.4064)
			(end 0.7874 0.4064)
			(stroke
				(width 0.1524)
				(type default)
			)
			(layer "F.SilkS")
		)
		(fp_line
			(start 0.7874 0.4064)
			(end -0.7874 0.4064)
			(stroke
				(width 0.1524)
				(type default)
			)
			(layer "F.SilkS")
		)
		(fp_line
			(start -0.67945 -0.305054)
			(end -0.12065 -0.305054)
			(stroke
				(width 0.1)
				(type default)
			)
			(layer "F.Fab")
		)
		(fp_line
			(start -0.67945 0.3048)
			(end -0.67945 -0.305054)
			(stroke
				(width 0.1)
				(type default)
			)
			(layer "F.Fab")
		)
		(fp_line
			(start -0.12065 -0.305054)
			(end -0.12065 -0.2794)
			(stroke
				(width 0.1)
				(type default)
			)
			(layer "F.Fab")
		)
		(fp_line
			(start -0.12065 -0.2794)
			(end 0.12065 -0.2794)
			(stroke
				(width 0.1)
				(type default)
			)
			(layer "F.Fab")
		)
		(fp_line
			(start -0.12065 0.2794)
			(end -0.12065 0.3048)
			(stroke
				(width 0.1)
				(type default)
			)
			(layer "F.Fab")
		)
		(fp_line
			(start -0.12065 0.3048)
			(end -0.67945 0.3048)
			(stroke
				(width 0.1)
				(type default)
			)
			(layer "F.Fab")
		)
		(fp_line
			(start 0.120396 0.2794)
			(end -0.12065 0.2794)
			(stroke
				(width 0.1)
				(type default)
			)
			(layer "F.Fab")
		)
		(fp_line
			(start 0.120396 0.3048)
			(end 0.120396 0.2794)
			(stroke
				(width 0.1)
				(type default)
			)
			(layer "F.Fab")
		)
		(fp_line
			(start 0.12065 -0.3048)
			(end 0.67945 -0.3048)
			(stroke
				(width 0.1)
				(type default)
			)
			(layer "F.Fab")
		)
		(fp_line
			(start 0.12065 -0.2794)
			(end 0.12065 -0.3048)
			(stroke
				(width 0.1)
				(type default)
			)
			(layer "F.Fab")
		)
		(fp_line
			(start 0.67945 -0.3048)
			(end 0.67945 0.3048)
			(stroke
				(width 0.1)
				(type default)
			)
			(layer "F.Fab")
		)
		(fp_line
			(start 0.67945 0.3048)
			(end 0.120396 0.3048)
			(stroke
				(width 0.1)
				(type default)
			)
			(layer "F.Fab")
		)
		(pad "1" smd circle
			(at -0.40005 0)
			(size 0 0)
			(layers "F.Cu" "F.Mask" "F.Paste")
			(net "FM_CLK_EN_R")
		)
		(pad "2" smd circle
			(at 0.40005 0)
			(size 0 0)
			(layers "F.Cu" "F.Mask" "F.Paste")
			(net "P3V3")
		)
	)
	(footprint ""
		(layer "F.Cu")
		(at 331.978 -245.237 -90)
		(property "Reference" "R1784"
			(at 0 0 270)
			(layer "F.SilkS")
			(hide yes)
			(effects
				(font
					(size 1.27 1.27)
				)
			)
		)
		(property "Value" ""
			(at 0 0 270)
			(layer "F.Fab")
			(effects
				(font
					(size 1.27 1.27)
				)
			)
		)
		(duplicate_pad_numbers_are_jumpers no)
		(fp_line
			(start -0.7874 0.4064)
			(end -0.7874 -0.4064)
			(stroke
				(width 0.1524)
				(type default)
			)
			(layer "F.SilkS")
		)
		(fp_line
			(start 0.7874 0.4064)
			(end -0.7874 0.4064)
			(stroke
				(width 0.1524)
				(type default)
			)
			(layer "F.SilkS")
		)
		(fp_line
			(start -0.7874 -0.4064)
			(end 0.7874 -0.4064)
			(stroke
				(width 0.1524)
				(type default)
			)
			(layer "F.SilkS")
		)
		(fp_line
			(start 0.7874 -0.4064)
			(end 0.7874 0.4064)
			(stroke
				(width 0.1524)
				(type default)
			)
			(layer "F.SilkS")
		)
		(fp_line
			(start -0.67945 0.3048)
			(end -0.67945 -0.305054)
			(stroke
				(width 0.1)
				(type default)
			)
			(layer "F.Fab")
		)
		(fp_line
			(start -0.12065 0.3048)
			(end -0.67945 0.3048)
			(stroke
				(width 0.1)
				(type default)
			)
			(layer "F.Fab")
		)
		(fp_line
			(start 0.120396 0.3048)
			(end 0.120396 0.2794)
			(stroke
				(width 0.1)
				(type default)
			)
			(layer "F.Fab")
		)
		(fp_line
			(start 0.67945 0.3048)
			(end 0.120396 0.3048)
			(stroke
				(width 0.1)
				(type default)
			)
			(layer "F.Fab")
		)
		(fp_line
			(start -0.12065 0.2794)
			(end -0.12065 0.3048)
			(stroke
				(width 0.1)
				(type default)
			)
			(layer "F.Fab")
		)
		(fp_line
			(start 0.120396 0.2794)
			(end -0.12065 0.2794)
			(stroke
				(width 0.1)
				(type default)
			)
			(layer "F.Fab")
		)
		(fp_line
			(start -0.12065 -0.2794)
			(end 0.12065 -0.2794)
			(stroke
				(width 0.1)
				(type default)
			)
			(layer "F.Fab")
		)
		(fp_line
			(start 0.12065 -0.2794)
			(end 0.12065 -0.3048)
			(stroke
				(width 0.1)
				(type default)
			)
			(layer "F.Fab")
		)
		(fp_line
			(start 0.12065 -0.3048)
			(end 0.67945 -0.3048)
			(stroke
				(width 0.1)
				(type default)
			)
			(layer "F.Fab")
		)
		(fp_line
			(start 0.67945 -0.3048)
			(end 0.67945 0.3048)
			(stroke
				(width 0.1)
				(type default)
			)
			(layer "F.Fab")
		)
		(fp_line
			(start -0.67945 -0.305054)
			(end -0.12065 -0.305054)
			(stroke
				(width 0.1)
				(type default)
			)
			(layer "F.Fab")
		)
		(fp_line
			(start -0.12065 -0.305054)
			(end -0.12065 -0.2794)
			(stroke
				(width 0.1)
				(type default)
			)
			(layer "F.Fab")
		)
		(pad "1" smd circle
			(at -0.40005 0 270)
			(size 0 0)
			(layers "F.Cu" "F.Mask" "F.Paste")
			(net "P3V3_AUX")
		)
		(pad "2" smd circle
			(at 0.40005 0 270)
			(size 0 0)
			(layers "F.Cu" "F.Mask" "F.Paste")
			(net "RST_MB_PERST_0_N")
		)
	)
	(footprint ""
		(layer "F.Cu")
		(at 428.837852 -350.098614 90)
		(property "Reference" "C2458"
			(at 0 0 90)
			(layer "F.SilkS")
			(hide yes)
			(effects
				(font
					(size 1.27 1.27)
				)
			)
		)
		(property "Value" ""
			(at 0 0 90)
			(layer "F.Fab")
			(effects
				(font
					(size 1.27 1.27)
				)
			)
		)
		(duplicate_pad_numbers_are_jumpers no)
		(fp_line
			(start 0.299974 -0.150114)
			(end 0.299974 0.150114)
			(stroke
				(width 0.1)
				(type default)
			)
			(layer "F.Fab")
		)
		(fp_line
			(start -0.299974 -0.150114)
			(end 0.299974 -0.150114)
			(stroke
				(width 0.1)
				(type default)
			)
			(layer "F.Fab")
		)
		(fp_line
			(start 0.299974 0.150114)
			(end -0.299974 0.150114)
			(stroke
				(width 0.1)
				(type default)
			)
			(layer "F.Fab")
		)
		(fp_line
			(start -0.299974 0.150114)
			(end -0.299974 -0.150114)
			(stroke
				(width 0.1)
				(type default)
			)
			(layer "F.Fab")
		)
		(pad "1" smd rect
			(at -0.2667 0 90)
			(size 0.3048 0.381)
			(layers "F.Cu" "F.Mask" "F.Paste")
			(net "P5E_PEX3_STN4_TX_DN<70>")
		)
		(pad "2" smd rect
			(at 0.2667 0 90)
			(size 0.3048 0.381)
			(layers "F.Cu" "F.Mask" "F.Paste")
			(net "P5E_PEX3_STN4_TX_C_DN<70>")
		)
	)
	(footprint ""
		(layer "F.Cu")
		(at 168.367964 -51.019456)
		(property "Reference" "PC375"
			(at 0 0 0)
			(layer "F.SilkS")
			(hide yes)
			(effects
				(font
					(size 1.27 1.27)
				)
			)
		)
		(property "Value" ""
			(at 0 0 0)
			(layer "F.Fab")
			(effects
				(font
					(size 1.27 1.27)
				)
			)
		)
		(duplicate_pad_numbers_are_jumpers no)
		(fp_line
			(start -0.7874 -0.4064)
			(end 0.7874 -0.4064)
			(stroke
				(width 0.1524)
				(type default)
			)
			(layer "F.SilkS")
		)
		(fp_line
			(start -0.7874 0.4064)
			(end -0.7874 -0.4064)
			(stroke
				(width 0.1524)
				(type default)
			)
			(layer "F.SilkS")
		)
		(fp_line
			(start 0.7874 -0.4064)
			(end 0.7874 0.4064)
			(stroke
				(width 0.1524)
				(type default)
			)
			(layer "F.SilkS")
		)
		(fp_line
			(start 0.7874 0.4064)
			(end -0.7874 0.4064)
			(stroke
				(width 0.1524)
				(type default)
			)
			(layer "F.SilkS")
		)
		(fp_line
			(start -0.6858 -0.3048)
			(end -0.1016 -0.3048)
			(stroke
				(width 0.1)
				(type default)
			)
			(layer "F.Fab")
		)
		(fp_line
			(start -0.6858 0.3048)
			(end -0.6858 -0.3048)
			(stroke
				(width 0.1)
				(type default)
			)
			(layer "F.Fab")
		)
		(fp_line
			(start -0.1016 -0.3048)
			(end -0.1016 -0.2794)
			(stroke
				(width 0.1)
				(type default)
			)
			(layer "F.Fab")
		)
		(fp_line
			(start -0.1016 -0.2794)
			(end 0.1016 -0.2794)
			(stroke
				(width 0.1)
				(type default)
			)
			(layer "F.Fab")
		)
		(fp_line
			(start -0.1016 0.2794)
			(end -0.1016 0.3048)
			(stroke
				(width 0.1)
				(type default)
			)
			(layer "F.Fab")
		)
		(fp_line
			(start -0.1016 0.3048)
			(end -0.6858 0.3048)
			(stroke
				(width 0.1)
				(type default)
			)
			(layer "F.Fab")
		)
		(fp_line
			(start 0.1016 -0.3048)
			(end 0.6858 -0.3048)
			(stroke
				(width 0.1)
				(type default)
			)
			(layer "F.Fab")
		)
		(fp_line
			(start 0.1016 -0.2794)
			(end 0.1016 -0.3048)
			(stroke
				(width 0.1)
				(type default)
			)
			(layer "F.Fab")
		)
		(fp_line
			(start 0.1016 0.2794)
			(end -0.1016 0.2794)
			(stroke
				(width 0.1)
				(type default)
			)
			(layer "F.Fab")
		)
		(fp_line
			(start 0.1016 0.3048)
			(end 0.1016 0.2794)
			(stroke
				(width 0.1)
				(type default)
			)
			(layer "F.Fab")
		)
		(fp_line
			(start 0.6858 -0.3048)
			(end 0.6858 0.3048)
			(stroke
				(width 0.1)
				(type default)
			)
			(layer "F.Fab")
		)
		(fp_line
			(start 0.6858 0.3048)
			(end 0.1016 0.3048)
			(stroke
				(width 0.1)
				(type default)
			)
			(layer "F.Fab")
		)
		(pad "1" smd rect
			(at -0.40005 0 180)
			(size 0.4572 0.508)
			(layers "F.Cu" "F.Mask" "F.Paste")
			(net "P12V_SSD5_SS")
		)
		(pad "2" smd rect
			(at 0.40005 0 180)
			(size 0.4572 0.508)
			(layers "F.Cu" "F.Mask" "F.Paste")
			(net "GND")
		)
	)
	(footprint ""
		(layer "F.Cu")
		(at 201.970386 -302.308514 90)
		(property "Reference" "R6718"
			(at 0 0 90)
			(layer "F.SilkS")
			(hide yes)
			(effects
				(font
					(size 1.27 1.27)
				)
			)
		)
		(property "Value" ""
			(at 0 0 90)
			(layer "F.Fab")
			(effects
				(font
					(size 1.27 1.27)
				)
			)
		)
		(duplicate_pad_numbers_are_jumpers no)
		(fp_line
			(start 0.7874 -0.4064)
			(end 0.7874 0.4064)
			(stroke
				(width 0.1524)
				(type default)
			)
			(layer "F.SilkS")
		)
		(fp_line
			(start -0.7874 -0.4064)
			(end 0.7874 -0.4064)
			(stroke
				(width 0.1524)
				(type default)
			)
			(layer "F.SilkS")
		)
		(fp_line
			(start 0.7874 0.4064)
			(end -0.7874 0.4064)
			(stroke
				(width 0.1524)
				(type default)
			)
			(layer "F.SilkS")
		)
		(fp_line
			(start -0.7874 0.4064)
			(end -0.7874 -0.4064)
			(stroke
				(width 0.1524)
				(type default)
			)
			(layer "F.SilkS")
		)
		(fp_line
			(start -0.12065 -0.305054)
			(end -0.12065 -0.2794)
			(stroke
				(width 0.1)
				(type default)
			)
			(layer "F.Fab")
		)
		(fp_line
			(start -0.67945 -0.305054)
			(end -0.12065 -0.305054)
			(stroke
				(width 0.1)
				(type default)
			)
			(layer "F.Fab")
		)
		(fp_line
			(start 0.67945 -0.3048)
			(end 0.67945 0.3048)
			(stroke
				(width 0.1)
				(type default)
			)
			(layer "F.Fab")
		)
		(fp_line
			(start 0.12065 -0.3048)
			(end 0.67945 -0.3048)
			(stroke
				(width 0.1)
				(type default)
			)
			(layer "F.Fab")
		)
		(fp_line
			(start 0.12065 -0.2794)
			(end 0.12065 -0.3048)
			(stroke
				(width 0.1)
				(type default)
			)
			(layer "F.Fab")
		)
		(fp_line
			(start -0.12065 -0.2794)
			(end 0.12065 -0.2794)
			(stroke
				(width 0.1)
				(type default)
			)
			(layer "F.Fab")
		)
		(fp_line
			(start 0.120396 0.2794)
			(end -0.12065 0.2794)
			(stroke
				(width 0.1)
				(type default)
			)
			(layer "F.Fab")
		)
		(fp_line
			(start -0.12065 0.2794)
			(end -0.12065 0.3048)
			(stroke
				(width 0.1)
				(type default)
			)
			(layer "F.Fab")
		)
		(fp_line
			(start 0.67945 0.3048)
			(end 0.120396 0.3048)
			(stroke
				(width 0.1)
				(type default)
			)
			(layer "F.Fab")
		)
		(fp_line
			(start 0.120396 0.3048)
			(end 0.120396 0.2794)
			(stroke
				(width 0.1)
				(type default)
			)
			(layer "F.Fab")
		)
		(fp_line
			(start -0.12065 0.3048)
			(end -0.67945 0.3048)
			(stroke
				(width 0.1)
				(type default)
			)
			(layer "F.Fab")
		)
		(fp_line
			(start -0.67945 0.3048)
			(end -0.67945 -0.305054)
			(stroke
				(width 0.1)
				(type default)
			)
			(layer "F.Fab")
		)
		(pad "1" smd circle
			(at -0.40005 0 90)
			(size 0 0)
			(layers "F.Cu" "F.Mask" "F.Paste")
			(net "SMB_PEX1_SLAVE1_SCL")
		)
		(pad "2" smd circle
			(at 0.40005 0 90)
			(size 0 0)
			(layers "F.Cu" "F.Mask" "F.Paste")
			(net "SMB_PEX1_R_SCL")
		)
	)
	(footprint ""
		(layer "F.Cu")
		(at 243.793264 -116.311426 -90)
		(property "Reference" "Q216"
			(at 0.131826 1.933194 90)
			(unlocked yes)
			(layer "F.SilkS")
			(effects
				(font
					(size 0.7874 0.5842)
					(thickness 0.1524)
				)
			)
		)
		(property "Value" ""
			(at 0 0 270)
			(layer "F.Fab")
			(effects
				(font
					(size 1.27 1.27)
				)
			)
		)
		(duplicate_pad_numbers_are_jumpers no)
		(fp_line
			(start -1.376172 1.199896)
			(end -1.376172 -1.199896)
			(stroke
				(width 0.1524)
				(type default)
			)
			(layer "F.SilkS")
		)
		(fp_line
			(start 1.376172 1.199896)
			(end -1.376172 1.199896)
			(stroke
				(width 0.1524)
				(type default)
			)
			(layer "F.SilkS")
		)
		(fp_line
			(start 0 -0.762)
			(end 0.508 -1.199896)
			(stroke
				(width 0.1524)
				(type default)
			)
			(layer "F.SilkS")
		)
		(fp_line
			(start -1.376172 -1.199896)
			(end -0.508 -1.199896)
			(stroke
				(width 0.1524)
				(type default)
			)
			(layer "F.SilkS")
		)
		(fp_line
			(start -0.508 -1.199896)
			(end 0 -0.762)
			(stroke
				(width 0.1524)
				(type default)
			)
			(layer "F.SilkS")
		)
		(fp_line
			(start 0.508 -1.199896)
			(end 1.376172 -1.199896)
			(stroke
				(width 0.1524)
				(type default)
			)
			(layer "F.SilkS")
		)
		(fp_line
			(start 1.376172 -1.199896)
			(end 1.376172 1.199896)
			(stroke
				(width 0.1524)
				(type default)
			)
			(layer "F.SilkS")
		)
		(fp_poly
			(pts
				(xy -1.151636 -1.323086) (xy -1.42113 -2.131314) (xy -1.959864 -1.59258)
			)
			(stroke
				(width 0)
				(type default)
			)
			(fill yes)
			(layer "F.SilkS")
		)
		(fp_line
			(start -0.674878 1.100074)
			(end -0.674878 -1.100074)
			(stroke
				(width 0.1)
				(type default)
			)
			(layer "F.Fab")
		)
		(fp_line
			(start 0.674878 1.100074)
			(end -0.674878 1.100074)
			(stroke
				(width 0.1)
				(type default)
			)
			(layer "F.Fab")
		)
		(fp_line
			(start -0.674878 -1.100074)
			(end 0.674878 -1.100074)
			(stroke
				(width 0.1)
				(type default)
			)
			(layer "F.Fab")
		)
		(fp_line
			(start 0.674878 -1.100074)
			(end 0.674878 1.100074)
			(stroke
				(width 0.1)
				(type default)
			)
			(layer "F.Fab")
		)
		(fp_poly
			(pts
				(xy -1.4605 -0.7493) (xy -2.2225 -1.1303) (xy -2.2225 -0.3683)
			)
			(stroke
				(width 0)
				(type default)
			)
			(fill yes)
			(layer "F.Fab")
		)
		(pad "1" smd rect
			(at -0.899922 -0.750062 180)
			(size 0.6096 0.6096)
			(layers "F.Cu" "F.Mask" "F.Paste")
			(net "GND")
		)
		(pad "2" smd rect
			(at -0.899922 0 180)
			(size 0.4064 0.6096)
			(layers "F.Cu" "F.Mask" "F.Paste")
			(net "P3V3_NIC4_PG_G1")
		)
		(pad "3" smd rect
			(at -0.899922 0.750062 180)
			(size 0.6096 0.6096)
			(layers "F.Cu" "F.Mask" "F.Paste")
			(net "PWRGD_P3V3_NIC4_D")
		)
		(pad "4" smd rect
			(at 0.899922 0.750062 180)
			(size 0.6096 0.6096)
			(layers "F.Cu" "F.Mask" "F.Paste")
			(net "GND")
		)
		(pad "5" smd rect
			(at 0.899922 0 180)
			(size 0.4064 0.6096)
			(layers "F.Cu" "F.Mask" "F.Paste")
			(net "P3V3_NIC4_PG_G2")
		)
		(pad "6" smd rect
			(at 0.899922 -0.750062 180)
			(size 0.6096 0.6096)
			(layers "F.Cu" "F.Mask" "F.Paste")
			(net "P3V3_NIC4_PG_G2")
		)
	)
)
